(kicad_pcb
	(version 20260206)
	(generator "pcbnew")
	(generator_version "10.0")
	(general
		(thickness 1.6)
		(legacy_teardrops no)
	)
	(paper "A4")
	(title_block
		(title "fcb — Lightning_FCB_BRD.brd")
		(comment 1 "Lightning (Wiwynn / Facebook NVMe JBOF) / footprints 320-327 of 495")
	)
	(layers
		(0 "F.Cu" signal "TOP")
		(4 "In1.Cu" signal "L2GND")
		(6 "In2.Cu" signal "L3VCC")
		(2 "B.Cu" signal "BOTTOM")
		(9 "F.Adhes" user "F.Adhesive")
		(11 "B.Adhes" user "B.Adhesive")
		(13 "F.Paste" user "Package Geometry/Pastemask Top")
		(15 "B.Paste" user "Package Geometry/Pastemask Bottom")
		(5 "F.SilkS" user "Ref Des/Silkscreen Top")
		(7 "B.SilkS" user "Ref Des/Silkscreen Bottom")
		(1 "F.Mask" user "Board Geometry/Soldermask Top")
		(3 "B.Mask" user "Board Geometry/Soldermask Bottom")
		(17 "Dwgs.User" user "User.Drawings")
		(19 "Cmts.User" user "User.Comments")
		(21 "Eco1.User" user "User.Eco1")
		(23 "Eco2.User" user "User.Eco2")
		(25 "Edge.Cuts" user "Board Geometry/Outline")
		(27 "Margin" user)
		(31 "F.CrtYd" user "Package Geometry/Place Bound Top")
		(29 "B.CrtYd" user "Package Geometry/Place Bound Bottom")
		(35 "F.Fab" user "Ref Des/Assembly Top")
		(33 "B.Fab" user "Ref Des/Assembly Bottom")
	)
	(footprint ""
		(layer "F.Cu")
		(at 14.5796 -171.4754)
		(property "Reference" "R49"
			(at 0 0 0)
			(layer "F.SilkS")
			(hide yes)
			(effects
				(font
					(size 1.27 1.27)
				)
			)
		)
		(property "Value" "4K7R2F-GP"
			(at 0.064008 -3.993896 0)
			(unlocked yes)
			(layer "F.Fab")
			(hide yes)
			(effects
				(font
					(size 1.016 1.016)
					(thickness 0.1524)
				)
			)
		)
		(property "Device Type" "R402H16"
			(at 0.064008 -5.517896 0)
			(unlocked yes)
			(layer "F.Fab")
			(hide yes)
			(effects
				(font
					(size 1.016 1.016)
					(thickness 0.1524)
				)
			)
		)
		(duplicate_pad_numbers_are_jumpers no)
		(fp_line
			(start -0.508 -0.9398)
			(end -0.508 0.9398)
			(stroke
				(width 0.1524)
				(type default)
			)
			(layer "F.SilkS")
		)
		(fp_line
			(start 0.508 -0.9398)
			(end -0.508 -0.9398)
			(stroke
				(width 0.1524)
				(type default)
			)
			(layer "F.SilkS")
		)
		(fp_rect
			(start -0.508 0.9398)
			(end 0.508 -0.9398)
			(stroke
				(width 0)
				(type default)
			)
			(fill no)
			(layer "F.CrtYd")
		)
		(fp_rect
			(start -0.508 0.9398)
			(end 0.508 -0.9398)
			(stroke
				(width 0)
				(type default)
			)
			(fill no)
			(layer "F.Fab")
		)
		(pad "1" smd custom
			(at 0 -0.4445)
			(size 0.1397 0.1397)
			(layers "F.Cu" "F.Mask" "F.Paste")
			(net "P3V3")
			(options
				(clearance outline)
				(anchor circle)
			)
			(primitives
				(gr_poly
					(pts
						(arc
							(start -0.1778 -0.2794)
							(mid -0.249642 -0.249642)
							(end -0.2794 -0.1778)
						)
						(arc
							(start -0.2794 0.1778)
							(mid -0.249642 0.249642)
							(end -0.1778 0.2794)
						)
						(arc
							(start 0.1778 0.2794)
							(mid 0.249642 0.249642)
							(end 0.2794 0.1778)
						)
						(arc
							(start 0.2794 -0.1778)
							(mid 0.249642 -0.249642)
							(end 0.1778 -0.2794)
						)
					)
					(width 0)
					(fill yes)
				)
			)
		)
		(pad "2" smd custom
			(at 0 0.4445)
			(size 0.1397 0.1397)
			(layers "F.Cu" "F.Mask" "F.Paste")
			(net "SEB_PEER_1A_1B_HB_OUT")
			(options
				(clearance outline)
				(anchor circle)
			)
			(primitives
				(gr_poly
					(pts
						(arc
							(start -0.1778 -0.2794)
							(mid -0.249642 -0.249642)
							(end -0.2794 -0.1778)
						)
						(arc
							(start -0.2794 0.1778)
							(mid -0.249642 0.249642)
							(end -0.1778 0.2794)
						)
						(arc
							(start 0.1778 0.2794)
							(mid 0.249642 0.249642)
							(end 0.2794 0.1778)
						)
						(arc
							(start 0.2794 -0.1778)
							(mid 0.249642 -0.249642)
							(end 0.1778 -0.2794)
						)
					)
					(width 0)
					(fill yes)
				)
			)
		)
	)
	(footprint ""
		(layer "F.Cu")
		(at 16.67129 -175.540924 180)
		(property "Reference" "C9"
			(at 0 0 180)
			(layer "F.SilkS")
			(hide yes)
			(effects
				(font
					(size 1.27 1.27)
				)
			)
		)
		(property "Value" "SC1U16V3KX-5GP"
			(at 0 -2.8194 180)
			(unlocked yes)
			(layer "F.Fab")
			(hide yes)
			(effects
				(font
					(size 1.016 1.016)
					(thickness 0.1524)
				)
			)
		)
		(property "Device Type" "C603H36"
			(at 0 -4.3434 180)
			(unlocked yes)
			(layer "F.Fab")
			(hide yes)
			(effects
				(font
					(size 1.016 1.016)
					(thickness 0.1524)
				)
			)
		)
		(duplicate_pad_numbers_are_jumpers no)
		(fp_line
			(start 0.508 0)
			(end -0.508 0)
			(stroke
				(width 0.2032)
				(type default)
			)
			(layer "F.SilkS")
		)
		(fp_rect
			(start -0.5842 1.3335)
			(end 0.5842 -1.3335)
			(stroke
				(width 0)
				(type default)
			)
			(fill no)
			(layer "F.CrtYd")
		)
		(fp_rect
			(start -0.5842 1.3335)
			(end 0.5842 -1.3335)
			(stroke
				(width 0)
				(type default)
			)
			(fill no)
			(layer "F.Fab")
		)
		(pad "1" smd custom
			(at 0 -0.762 180)
			(size 0.2159 0.2159)
			(layers "F.Cu" "F.Mask" "F.Paste")
			(net "P3V3")
			(options
				(clearance outline)
				(anchor circle)
			)
			(primitives
				(gr_poly
					(pts
						(arc
							(start -0.3302 -0.4318)
							(mid -0.402042 -0.402042)
							(end -0.4318 -0.3302)
						)
						(arc
							(start -0.4318 0.3302)
							(mid -0.402042 0.402042)
							(end -0.3302 0.4318)
						)
						(arc
							(start 0.3302 0.4318)
							(mid 0.402042 0.402042)
							(end 0.4318 0.3302)
						)
						(arc
							(start 0.4318 -0.3302)
							(mid 0.402042 -0.402042)
							(end 0.3302 -0.4318)
						)
					)
					(width 0)
					(fill yes)
				)
			)
		)
		(pad "2" smd custom
			(at 0 0.762 180)
			(size 0.2159 0.2159)
			(layers "F.Cu" "F.Mask" "F.Paste")
			(net "GND")
			(options
				(clearance outline)
				(anchor circle)
			)
			(primitives
				(gr_poly
					(pts
						(arc
							(start -0.3302 -0.4318)
							(mid -0.402042 -0.402042)
							(end -0.4318 -0.3302)
						)
						(arc
							(start -0.4318 0.3302)
							(mid -0.402042 0.402042)
							(end -0.3302 0.4318)
						)
						(arc
							(start 0.3302 0.4318)
							(mid 0.402042 0.402042)
							(end 0.4318 0.3302)
						)
						(arc
							(start 0.4318 -0.3302)
							(mid 0.402042 -0.402042)
							(end 0.3302 -0.4318)
						)
					)
					(width 0)
					(fill yes)
				)
			)
		)
	)
	(footprint ""
		(layer "F.Cu")
		(at 27.305 -378.079)
		(property "Reference" "PR2"
			(at 0 0 0)
			(layer "F.SilkS")
			(hide yes)
			(effects
				(font
					(size 1.27 1.27)
				)
			)
		)
		(property "Value" "10R2F-L-GP"
			(at 0.064008 -3.993896 0)
			(unlocked yes)
			(layer "F.Fab")
			(hide yes)
			(effects
				(font
					(size 1.016 1.016)
					(thickness 0.1524)
				)
			)
		)
		(property "Device Type" "R402H14"
			(at 0.064008 -5.517896 0)
			(unlocked yes)
			(layer "F.Fab")
			(hide yes)
			(effects
				(font
					(size 1.016 1.016)
					(thickness 0.1524)
				)
			)
		)
		(duplicate_pad_numbers_are_jumpers no)
		(fp_line
			(start -0.508 -0.9398)
			(end -0.508 0.9398)
			(stroke
				(width 0.1524)
				(type default)
			)
			(layer "F.SilkS")
		)
		(fp_line
			(start 0.508 -0.9398)
			(end -0.508 -0.9398)
			(stroke
				(width 0.1524)
				(type default)
			)
			(layer "F.SilkS")
		)
		(fp_rect
			(start -0.508 0.9398)
			(end 0.508 -0.9398)
			(stroke
				(width 0)
				(type default)
			)
			(fill no)
			(layer "F.CrtYd")
		)
		(fp_rect
			(start -0.508 0.9398)
			(end 0.508 -0.9398)
			(stroke
				(width 0)
				(type default)
			)
			(fill no)
			(layer "F.Fab")
		)
		(pad "1" smd custom
			(at 0 -0.4445)
			(size 0.1397 0.1397)
			(layers "F.Cu" "F.Mask" "F.Paste")
			(net "P12V_AUX")
			(options
				(clearance outline)
				(anchor circle)
			)
			(primitives
				(gr_poly
					(pts
						(arc
							(start -0.1778 -0.2794)
							(mid -0.249642 -0.249642)
							(end -0.2794 -0.1778)
						)
						(arc
							(start -0.2794 0.1778)
							(mid -0.249642 0.249642)
							(end -0.1778 0.2794)
						)
						(arc
							(start 0.1778 0.2794)
							(mid 0.249642 0.249642)
							(end 0.2794 0.1778)
						)
						(arc
							(start 0.2794 -0.1778)
							(mid 0.249642 -0.249642)
							(end 0.1778 -0.2794)
						)
					)
					(width 0)
					(fill yes)
				)
			)
		)
		(pad "2" smd custom
			(at 0 0.4445)
			(size 0.1397 0.1397)
			(layers "F.Cu" "F.Mask" "F.Paste")
			(net "ADM1276_VCC")
			(options
				(clearance outline)
				(anchor circle)
			)
			(primitives
				(gr_poly
					(pts
						(arc
							(start -0.1778 -0.2794)
							(mid -0.249642 -0.249642)
							(end -0.2794 -0.1778)
						)
						(arc
							(start -0.2794 0.1778)
							(mid -0.249642 0.249642)
							(end -0.1778 0.2794)
						)
						(arc
							(start 0.1778 0.2794)
							(mid 0.249642 0.249642)
							(end 0.2794 0.1778)
						)
						(arc
							(start 0.2794 -0.1778)
							(mid 0.249642 -0.249642)
							(end 0.1778 -0.2794)
						)
					)
					(width 0)
					(fill yes)
				)
			)
		)
	)
	(footprint ""
		(layer "F.Cu")
		(at 12.064492 -61.391546)
		(property "Reference" "C32"
			(at 0 0 0)
			(layer "F.SilkS")
			(hide yes)
			(effects
				(font
					(size 1.27 1.27)
				)
			)
		)
		(property "Value" "SC1U25V3KX-1-GP"
			(at 0 -2.8194 0)
			(unlocked yes)
			(layer "F.Fab")
			(hide yes)
			(effects
				(font
					(size 1.016 1.016)
					(thickness 0.1524)
				)
			)
		)
		(property "Device Type" "C603H36"
			(at 0 -4.3434 0)
			(unlocked yes)
			(layer "F.Fab")
			(hide yes)
			(effects
				(font
					(size 1.016 1.016)
					(thickness 0.1524)
				)
			)
		)
		(duplicate_pad_numbers_are_jumpers no)
		(fp_line
			(start 0.508 0)
			(end -0.508 0)
			(stroke
				(width 0.2032)
				(type default)
			)
			(layer "F.SilkS")
		)
		(fp_rect
			(start -0.5842 1.3335)
			(end 0.5842 -1.3335)
			(stroke
				(width 0)
				(type default)
			)
			(fill no)
			(layer "F.CrtYd")
		)
		(fp_rect
			(start -0.5842 1.3335)
			(end 0.5842 -1.3335)
			(stroke
				(width 0)
				(type default)
			)
			(fill no)
			(layer "F.Fab")
		)
		(pad "1" smd custom
			(at 0 -0.762)
			(size 0.2159 0.2159)
			(layers "F.Cu" "F.Mask" "F.Paste")
			(net "P12V")
			(options
				(clearance outline)
				(anchor circle)
			)
			(primitives
				(gr_poly
					(pts
						(arc
							(start -0.3302 -0.4318)
							(mid -0.402042 -0.402042)
							(end -0.4318 -0.3302)
						)
						(arc
							(start -0.4318 0.3302)
							(mid -0.402042 0.402042)
							(end -0.3302 0.4318)
						)
						(arc
							(start 0.3302 0.4318)
							(mid 0.402042 0.402042)
							(end 0.4318 0.3302)
						)
						(arc
							(start 0.4318 -0.3302)
							(mid 0.402042 -0.402042)
							(end 0.3302 -0.4318)
						)
					)
					(width 0)
					(fill yes)
				)
			)
		)
		(pad "2" smd custom
			(at 0 0.762)
			(size 0.2159 0.2159)
			(layers "F.Cu" "F.Mask" "F.Paste")
			(net "GND")
			(options
				(clearance outline)
				(anchor circle)
			)
			(primitives
				(gr_poly
					(pts
						(arc
							(start -0.3302 -0.4318)
							(mid -0.402042 -0.402042)
							(end -0.4318 -0.3302)
						)
						(arc
							(start -0.4318 0.3302)
							(mid -0.402042 0.402042)
							(end -0.3302 0.4318)
						)
						(arc
							(start 0.3302 0.4318)
							(mid 0.402042 0.402042)
							(end 0.4318 0.3302)
						)
						(arc
							(start 0.4318 -0.3302)
							(mid 0.402042 -0.402042)
							(end 0.3302 -0.4318)
						)
					)
					(width 0)
					(fill yes)
				)
			)
		)
	)
	(footprint ""
		(layer "F.Cu")
		(at 26.543 -237.871)
		(property "Reference" "R154"
			(at 0 0 0)
			(layer "F.SilkS")
			(hide yes)
			(effects
				(font
					(size 1.27 1.27)
				)
			)
		)
		(property "Value" "0R0805-PAD-2-GP"
			(at 0.0508 -2.7432 0)
			(unlocked yes)
			(layer "F.Fab")
			(hide yes)
			(effects
				(font
					(size 1.016 1.016)
					(thickness 0.1524)
				)
			)
		)
		(property "Device Type" "0R0805-PAD-1"
			(at 0.0508 -4.2672 0)
			(unlocked yes)
			(layer "F.Fab")
			(hide yes)
			(effects
				(font
					(size 1.016 1.016)
					(thickness 0.1524)
				)
			)
		)
		(duplicate_pad_numbers_are_jumpers no)
		(fp_line
			(start -0.889 -1.7018)
			(end 0.889 -1.7018)
			(stroke
				(width 0.1524)
				(type default)
			)
			(layer "F.SilkS")
		)
		(fp_line
			(start -0.889 1.7018)
			(end -0.889 -1.7018)
			(stroke
				(width 0.1524)
				(type default)
			)
			(layer "F.SilkS")
		)
		(fp_line
			(start 0.889 -1.7018)
			(end 0.889 1.7018)
			(stroke
				(width 0.1524)
				(type default)
			)
			(layer "F.SilkS")
		)
		(fp_line
			(start 0.889 1.7018)
			(end -0.889 1.7018)
			(stroke
				(width 0.1524)
				(type default)
			)
			(layer "F.SilkS")
		)
		(fp_rect
			(start -0.9652 1.778)
			(end 0.9652 -1.778)
			(stroke
				(width 0)
				(type default)
			)
			(fill no)
			(layer "F.CrtYd")
		)
		(fp_rect
			(start -0.9652 1.778)
			(end 0.9652 -1.778)
			(stroke
				(width 0)
				(type default)
			)
			(fill no)
			(layer "F.Fab")
		)
		(pad "1" smd rect
			(at 0 -0.9652)
			(size 1.397 1.5621)
			(drill
				(offset 0 0.20955)
			)
			(layers "F.Cu" "F.Mask" "F.Paste")
			(net "P3V3_LX_COPPER")
		)
		(pad "2" smd rect
			(at 0 0.9652)
			(size 1.397 1.568704)
			(drill
				(offset 0 -0.206248)
			)
			(layers "F.Cu" "F.Mask" "F.Paste")
			(net "P3V3")
		)
	)
	(footprint ""
		(layer "F.Cu")
		(at 15.113 -56.134 -90)
		(property "Reference" "R361"
			(at 0 0 270)
			(layer "F.SilkS")
			(hide yes)
			(effects
				(font
					(size 1.27 1.27)
				)
			)
		)
		(property "Value" "100R2J-2-GP"
			(at 0.064008 -3.993896 270)
			(unlocked yes)
			(layer "F.Fab")
			(hide yes)
			(effects
				(font
					(size 1.016 1.016)
					(thickness 0.1524)
				)
			)
		)
		(property "Device Type" "R402H14"
			(at 0.064008 -5.517896 270)
			(unlocked yes)
			(layer "F.Fab")
			(hide yes)
			(effects
				(font
					(size 1.016 1.016)
					(thickness 0.1524)
				)
			)
		)
		(duplicate_pad_numbers_are_jumpers no)
		(fp_line
			(start -0.508 -0.9398)
			(end -0.508 0.9398)
			(stroke
				(width 0.1524)
				(type default)
			)
			(layer "F.SilkS")
		)
		(fp_line
			(start 0.508 -0.9398)
			(end -0.508 -0.9398)
			(stroke
				(width 0.1524)
				(type default)
			)
			(layer "F.SilkS")
		)
		(fp_rect
			(start -0.508 0.9398)
			(end 0.508 -0.9398)
			(stroke
				(width 0)
				(type default)
			)
			(fill no)
			(layer "F.CrtYd")
		)
		(fp_rect
			(start -0.508 0.9398)
			(end 0.508 -0.9398)
			(stroke
				(width 0)
				(type default)
			)
			(fill no)
			(layer "F.Fab")
		)
		(pad "1" smd custom
			(at 0 -0.4445 270)
			(size 0.1397 0.1397)
			(layers "F.Cu" "F.Mask" "F.Paste")
			(net "LOWER_TRAY_ID")
			(options
				(clearance outline)
				(anchor circle)
			)
			(primitives
				(gr_poly
					(pts
						(arc
							(start -0.1778 -0.2794)
							(mid -0.249642 -0.249642)
							(end -0.2794 -0.1778)
						)
						(arc
							(start -0.2794 0.1778)
							(mid -0.249642 0.249642)
							(end -0.1778 0.2794)
						)
						(arc
							(start 0.1778 0.2794)
							(mid 0.249642 0.249642)
							(end 0.2794 0.1778)
						)
						(arc
							(start 0.2794 -0.1778)
							(mid 0.249642 -0.249642)
							(end 0.1778 -0.2794)
						)
					)
					(width 0)
					(fill yes)
				)
			)
		)
		(pad "2" smd custom
			(at 0 0.4445 270)
			(size 0.1397 0.1397)
			(layers "F.Cu" "F.Mask" "F.Paste")
			(net "GND")
			(options
				(clearance outline)
				(anchor circle)
			)
			(primitives
				(gr_poly
					(pts
						(arc
							(start -0.1778 -0.2794)
							(mid -0.249642 -0.249642)
							(end -0.2794 -0.1778)
						)
						(arc
							(start -0.2794 0.1778)
							(mid -0.249642 0.249642)
							(end -0.1778 0.2794)
						)
						(arc
							(start 0.1778 0.2794)
							(mid 0.249642 0.249642)
							(end 0.2794 0.1778)
						)
						(arc
							(start 0.2794 -0.1778)
							(mid 0.249642 -0.249642)
							(end 0.1778 -0.2794)
						)
					)
					(width 0)
					(fill yes)
				)
			)
		)
	)
	(footprint ""
		(layer "F.Cu")
		(at 22.225 -18.161 90)
		(property "Reference" "R75"
			(at 0 0 90)
			(layer "F.SilkS")
			(hide yes)
			(effects
				(font
					(size 1.27 1.27)
				)
			)
		)
		(property "Value" "10KR2F-2-GP"
			(at 0.064008 -3.993896 90)
			(unlocked yes)
			(layer "F.Fab")
			(hide yes)
			(effects
				(font
					(size 1.016 1.016)
					(thickness 0.1524)
				)
			)
		)
		(property "Device Type" "R402H16"
			(at 0.064008 -5.517896 90)
			(unlocked yes)
			(layer "F.Fab")
			(hide yes)
			(effects
				(font
					(size 1.016 1.016)
					(thickness 0.1524)
				)
			)
		)
		(duplicate_pad_numbers_are_jumpers no)
		(fp_line
			(start 0.508 -0.9398)
			(end -0.508 -0.9398)
			(stroke
				(width 0.1524)
				(type default)
			)
			(layer "F.SilkS")
		)
		(fp_line
			(start -0.508 -0.9398)
			(end -0.508 0.9398)
			(stroke
				(width 0.1524)
				(type default)
			)
			(layer "F.SilkS")
		)
		(fp_rect
			(start -0.508 0.9398)
			(end 0.508 -0.9398)
			(stroke
				(width 0)
				(type default)
			)
			(fill no)
			(layer "F.CrtYd")
		)
		(fp_rect
			(start -0.508 0.9398)
			(end 0.508 -0.9398)
			(stroke
				(width 0)
				(type default)
			)
			(fill no)
			(layer "F.Fab")
		)
		(pad "1" smd custom
			(at 0 -0.4445 90)
			(size 0.1397 0.1397)
			(layers "F.Cu" "F.Mask" "F.Paste")
			(net "FANIN_12")
			(options
				(clearance outline)
				(anchor circle)
			)
			(primitives
				(gr_poly
					(pts
						(arc
							(start -0.1778 -0.2794)
							(mid -0.249642 -0.249642)
							(end -0.2794 -0.1778)
						)
						(arc
							(start -0.2794 0.1778)
							(mid -0.249642 0.249642)
							(end -0.1778 0.2794)
						)
						(arc
							(start 0.1778 0.2794)
							(mid 0.249642 0.249642)
							(end 0.2794 0.1778)
						)
						(arc
							(start 0.2794 -0.1778)
							(mid 0.249642 -0.249642)
							(end 0.1778 -0.2794)
						)
					)
					(width 0)
					(fill yes)
				)
			)
		)
		(pad "2" smd custom
			(at 0 0.4445 90)
			(size 0.1397 0.1397)
			(layers "F.Cu" "F.Mask" "F.Paste")
			(net "GND")
			(options
				(clearance outline)
				(anchor circle)
			)
			(primitives
				(gr_poly
					(pts
						(arc
							(start -0.1778 -0.2794)
							(mid -0.249642 -0.249642)
							(end -0.2794 -0.1778)
						)
						(arc
							(start -0.2794 0.1778)
							(mid -0.249642 0.249642)
							(end -0.1778 0.2794)
						)
						(arc
							(start 0.1778 0.2794)
							(mid 0.249642 0.249642)
							(end 0.2794 0.1778)
						)
						(arc
							(start 0.2794 -0.1778)
							(mid 0.249642 -0.249642)
							(end 0.1778 -0.2794)
						)
					)
					(width 0)
					(fill yes)
				)
			)
		)
	)
	(footprint ""
		(layer "F.Cu")
		(at 26.15438 -376.08256 -90)
		(property "Reference" "PC2"
			(at 0 0 270)
			(layer "F.SilkS")
			(hide yes)
			(effects
				(font
					(size 1.27 1.27)
				)
			)
		)
		(property "Value" "SC10U25V5KX-GP"
			(at -0.0762 -6.1214 270)
			(unlocked yes)
			(layer "F.Fab")
			(hide yes)
			(effects
				(font
					(size 1.016 1.016)
					(thickness 0.1524)
				)
			)
		)
		(property "Device Type" "C805H56"
			(at -0.0762 -8.1534 270)
			(unlocked yes)
			(layer "F.Fab")
			(hide yes)
			(effects
				(font
					(size 1.016 1.016)
					(thickness 0.1524)
				)
			)
		)
		(duplicate_pad_numbers_are_jumpers no)
		(fp_line
			(start 0.635 0)
			(end -0.635 0)
			(stroke
				(width 0.508)
				(type default)
			)
			(layer "F.SilkS")
		)
		(fp_rect
			(start -0.9652 1.778)
			(end 0.9652 -1.778)
			(stroke
				(width 0)
				(type default)
			)
			(fill no)
			(layer "F.CrtYd")
		)
		(fp_poly
			(pts
				(xy -0.9652 -1.778) (xy 0.9652 -1.778) (xy 0.9652 1.778) (xy -0.9652 1.778)
			)
			(stroke
				(width 0)
				(type default)
			)
			(fill no)
			(layer "F.Fab")
		)
		(pad "1" smd rect
			(at 0 -0.9652 270)
			(size 1.397 1.143)
			(layers "F.Cu" "F.Mask" "F.Paste")
			(net "ADM1276_VCC")
		)
		(pad "2" smd rect
			(at 0 0.9652 270)
			(size 1.397 1.143)
			(layers "F.Cu" "F.Mask" "F.Paste")
			(net "GND")
		)
	)
)
